(kicad_pcb
	(version 20260206)
	(generator "pcbnew")
	(generator_version "10.0")
	(general
		(thickness 1.6)
		(legacy_teardrops no)
	)
	(paper "A4")
	(title_block
		(title "04192023_DAF0TMB3IC0_F0TG_MB_C_brd_V02_OCP.brd")
		(comment 1 "Grand Teton / footprint 2783 of 8354 (U26), pads 435-540 of 6102")
	)
	(layers
		(0 "F.Cu" signal "TOP")
		(4 "In1.Cu" signal "GND")
		(6 "In2.Cu" signal "IN1")
		(8 "In3.Cu" signal "GND1")
		(10 "In4.Cu" signal "IN2")
		(12 "In5.Cu" signal "GND2")
		(14 "In6.Cu" signal "IN3")
		(16 "In7.Cu" signal "GND3")
		(18 "In8.Cu" signal "VCC")
		(20 "In9.Cu" signal "VCC1")
		(22 "In10.Cu" signal "GND4")
		(24 "In11.Cu" signal "IN4")
		(26 "In12.Cu" signal "GND5")
		(28 "In13.Cu" signal "IN5")
		(30 "In14.Cu" signal "GND6")
		(32 "In15.Cu" signal "IN6")
		(34 "In16.Cu" signal "GND7")
		(2 "B.Cu" signal "BOTTOM")
		(9 "F.Adhes" user "F.Adhesive")
		(11 "B.Adhes" user "B.Adhesive")
		(13 "F.Paste" user "Package Geometry/Pastemask Top")
		(15 "B.Paste" user "Package Geometry/Pastemask Bottom")
		(5 "F.SilkS" user "Ref Des/Silkscreen Top")
		(7 "B.SilkS" user "Ref Des/Silkscreen Bottom")
		(1 "F.Mask" user "Board Geometry/Soldermask Top")
		(3 "B.Mask" user "Board Geometry/Soldermask Bottom")
		(17 "Dwgs.User" user "User.Drawings")
		(19 "Cmts.User" user "User.Comments")
		(21 "Eco1.User" user "User.Eco1")
		(23 "Eco2.User" user "User.Eco2")
		(25 "Edge.Cuts" user "Board Geometry/Outline")
		(27 "Margin" user)
		(31 "F.CrtYd" user "Package Geometry/Place Bound Top")
		(29 "B.CrtYd" user "Package Geometry/Place Bound Bottom")
		(35 "F.Fab" user "Ref Des/Assembly Top")
		(33 "B.Fab" user "Ref Des/Assembly Bottom")
	)
	(footprint ""
		(layer "F.Cu")
		(at 111.927894 -258.880356 180)
		(property "Reference" "U26"
			(at -45.05579 -61.794136 0)
			(unlocked yes)
			(layer "F.SilkS")
			(effects
				(font
					(size 0.7874 0.5842)
					(thickness 0.1524)
				)
			)
		)
		(property "Value" ""
			(at 0 0 180)
			(layer "F.Fab")
			(effects
				(font
					(size 1.27 1.27)
				)
			)
		)
		(duplicate_pad_numbers_are_jumpers no)
		(pad "AF14" smd circle
			(at -22.409912 -16.560038 180)
			(size 0.450088 0.450088)
			(layers "F.Cu" "F.Mask" "F.Paste")
			(net "M_H_CPU1_SA_DQS_DN<8>")
		)
		(pad "AF15" smd circle
			(at -21.470112 -16.560038 180)
			(size 0.450088 0.450088)
			(layers "F.Cu" "F.Mask" "F.Paste")
			(net "GND")
		)
		(pad "AF16" smd circle
			(at -20.530058 -16.560038 180)
			(size 0.450088 0.450088)
			(layers "F.Cu" "F.Mask" "F.Paste")
			(net "M_J_CPU1_SA_DQS_DN<3>")
		)
		(pad "AF17" smd circle
			(at -19.590004 -16.560038 180)
			(size 0.450088 0.450088)
			(layers "F.Cu" "F.Mask" "F.Paste")
			(net "GND")
		)
		(pad "AF18" smd circle
			(at -18.64995 -16.560038 180)
			(size 0.450088 0.450088)
			(layers "F.Cu" "F.Mask" "F.Paste")
			(net "M_J_CPU1_SA_DQS_DN<8>")
		)
		(pad "AF19" smd circle
			(at -17.709896 -16.560038 180)
			(size 0.450088 0.450088)
			(layers "F.Cu" "F.Mask" "F.Paste")
			(net "PVDDCR_SOC_P1")
		)
		(pad "AF20" smd circle
			(at -16.770096 -16.560038 180)
			(size 0.450088 0.450088)
			(layers "F.Cu" "F.Mask" "F.Paste")
			(net "M_I_CPU1_SA_DQS_DN<3>")
		)
		(pad "AF21" smd circle
			(at -15.830042 -16.560038 180)
			(size 0.450088 0.450088)
			(layers "F.Cu" "F.Mask" "F.Paste")
			(net "M_I_CPU1_SA_DQS_DN<8>")
		)
		(pad "AF22" smd circle
			(at -14.889988 -16.560038 180)
			(size 0.450088 0.450088)
			(layers "F.Cu" "F.Mask" "F.Paste")
			(net "GND")
		)
		(pad "AF23" smd circle
			(at -13.949934 -16.560038 180)
			(size 0.450088 0.450088)
			(layers "F.Cu" "F.Mask" "F.Paste")
			(net "PVDDCR_CPU0_P1")
		)
		(pad "AF24" smd circle
			(at -13.00988 -16.560038 180)
			(size 0.450088 0.450088)
			(layers "F.Cu" "F.Mask" "F.Paste")
			(net "PVDDCR_CPU0_P1")
		)
		(pad "AF25" smd circle
			(at -12.07008 -16.560038 180)
			(size 0.450088 0.450088)
			(layers "F.Cu" "F.Mask" "F.Paste")
			(net "GND")
		)
		(pad "AF26" smd circle
			(at -11.130026 -16.560038 180)
			(size 0.450088 0.450088)
			(layers "F.Cu" "F.Mask" "F.Paste")
			(net "PVDDCR_CPU0_P1")
		)
		(pad "AF27" smd circle
			(at -10.189972 -16.560038 180)
			(size 0.450088 0.450088)
			(layers "F.Cu" "F.Mask" "F.Paste")
			(net "PVDDCR_CPU0_P1")
		)
		(pad "AF28" smd circle
			(at -9.249918 -16.560038 180)
			(size 0.450088 0.450088)
			(layers "F.Cu" "F.Mask" "F.Paste")
			(net "GND")
		)
		(pad "AF29" smd circle
			(at -8.310118 -16.560038 180)
			(size 0.450088 0.450088)
			(layers "F.Cu" "F.Mask" "F.Paste")
			(net "PVDDCR_CPU0_P1")
		)
		(pad "AF30" smd circle
			(at -7.370064 -16.560038 180)
			(size 0.450088 0.450088)
			(layers "F.Cu" "F.Mask" "F.Paste")
			(net "PVDDCR_CPU0_P1")
		)
		(pad "AF31" smd circle
			(at -6.43001 -16.560038 180)
			(size 0.450088 0.450088)
			(layers "F.Cu" "F.Mask" "F.Paste")
			(net "GND")
		)
		(pad "AF32" smd circle
			(at -5.489956 -16.560038 180)
			(size 0.450088 0.450088)
			(layers "F.Cu" "F.Mask" "F.Paste")
			(net "PVDDCR_CPU0_P1")
		)
		(pad "AF33" smd circle
			(at -4.549902 -16.560038 180)
			(size 0.450088 0.450088)
			(layers "F.Cu" "F.Mask" "F.Paste")
			(net "PVDDCR_CPU0_P1")
		)
		(pad "AF34" smd circle
			(at -3.610102 -16.560038 180)
			(size 0.450088 0.450088)
			(layers "F.Cu" "F.Mask" "F.Paste")
			(net "GND")
		)
		(pad "AF35" smd circle
			(at -2.670048 -16.560038 180)
			(size 0.450088 0.450088)
			(layers "F.Cu" "F.Mask" "F.Paste")
			(net "GMI_CPU0_G0_CPU1_G2_TX_DN<0>")
		)
		(pad "AF36" smd circle
			(at -1.729994 -16.560038 180)
			(size 0.450088 0.450088)
			(layers "F.Cu" "F.Mask" "F.Paste")
			(net "GMI_CPU0_G0_CPU1_G2_TX_DP<0>")
		)
		(pad "AF37" smd circle
			(at -0.78994 -16.560038 180)
			(size 0.450088 0.450088)
			(layers "F.Cu" "F.Mask" "F.Paste")
			(net "GND")
		)
		(pad "AF39" smd circle
			(at 1.089914 -16.560038 180)
			(size 0.450088 0.450088)
			(layers "F.Cu" "F.Mask" "F.Paste")
			(net "GND")
		)
		(pad "AF40" smd circle
			(at 2.029968 -16.560038 180)
			(size 0.450088 0.450088)
			(layers "F.Cu" "F.Mask" "F.Paste")
			(net "GMI_CPU1_G0_CPU0_G2_TX_DP<15>")
		)
		(pad "AF41" smd circle
			(at 2.970022 -16.560038 180)
			(size 0.450088 0.450088)
			(layers "F.Cu" "F.Mask" "F.Paste")
			(net "GMI_CPU1_G0_CPU0_G2_TX_DN<15>")
		)
		(pad "AF42" smd circle
			(at 3.910076 -16.560038 180)
			(size 0.450088 0.450088)
			(layers "F.Cu" "F.Mask" "F.Paste")
			(net "GND")
		)
		(pad "AF43" smd circle
			(at 4.849876 -16.560038 180)
			(size 0.450088 0.450088)
			(layers "F.Cu" "F.Mask" "F.Paste")
			(net "PVDDCR_CPU0_P1")
		)
		(pad "AF44" smd circle
			(at 5.78993 -16.560038 180)
			(size 0.450088 0.450088)
			(layers "F.Cu" "F.Mask" "F.Paste")
			(net "PVDDCR_CPU0_P1")
		)
		(pad "AF45" smd circle
			(at 6.729984 -16.560038 180)
			(size 0.450088 0.450088)
			(layers "F.Cu" "F.Mask" "F.Paste")
			(net "GND")
		)
		(pad "AF46" smd circle
			(at 7.670038 -16.560038 180)
			(size 0.450088 0.450088)
			(layers "F.Cu" "F.Mask" "F.Paste")
			(net "PVDDCR_CPU0_P1")
		)
		(pad "AF47" smd circle
			(at 8.610092 -16.560038 180)
			(size 0.450088 0.450088)
			(layers "F.Cu" "F.Mask" "F.Paste")
			(net "PVDDCR_CPU0_P1")
		)
		(pad "AF48" smd circle
			(at 9.549892 -16.560038 180)
			(size 0.450088 0.450088)
			(layers "F.Cu" "F.Mask" "F.Paste")
			(net "GND")
		)
		(pad "AF49" smd circle
			(at 10.489946 -16.560038 180)
			(size 0.450088 0.450088)
			(layers "F.Cu" "F.Mask" "F.Paste")
			(net "PVDDCR_CPU0_P1")
		)
		(pad "AF50" smd circle
			(at 11.43 -16.560038 180)
			(size 0.450088 0.450088)
			(layers "F.Cu" "F.Mask" "F.Paste")
			(net "PVDDCR_CPU0_P1")
		)
		(pad "AF51" smd circle
			(at 12.370054 -16.560038 180)
			(size 0.450088 0.450088)
			(layers "F.Cu" "F.Mask" "F.Paste")
			(net "GND")
		)
		(pad "AF52" smd circle
			(at 13.310108 -16.560038 180)
			(size 0.450088 0.450088)
			(layers "F.Cu" "F.Mask" "F.Paste")
			(net "PVDDCR_CPU0_P1")
		)
		(pad "AF53" smd circle
			(at 14.249908 -16.560038 180)
			(size 0.450088 0.450088)
			(layers "F.Cu" "F.Mask" "F.Paste")
			(net "PVDDCR_CPU0_P1")
		)
		(pad "AF54" smd circle
			(at 15.189962 -16.560038 180)
			(size 0.450088 0.450088)
			(layers "F.Cu" "F.Mask" "F.Paste")
			(net "GND")
		)
		(pad "AF55" smd circle
			(at 16.130016 -16.560038 180)
			(size 0.450088 0.450088)
			(layers "F.Cu" "F.Mask" "F.Paste")
			(net "M_C_CPU1_SA_DQS_DN<8>")
		)
		(pad "AF56" smd circle
			(at 17.07007 -16.560038 180)
			(size 0.450088 0.450088)
			(layers "F.Cu" "F.Mask" "F.Paste")
			(net "M_C_CPU1_SA_DQS_DN<3>")
		)
		(pad "AF57" smd circle
			(at 18.010124 -16.560038 180)
			(size 0.450088 0.450088)
			(layers "F.Cu" "F.Mask" "F.Paste")
			(net "PVDDIO_P1")
		)
		(pad "AF58" smd circle
			(at 18.949924 -16.560038 180)
			(size 0.450088 0.450088)
			(layers "F.Cu" "F.Mask" "F.Paste")
			(net "M_D_CPU1_SA_DQS_DN<8>")
		)
		(pad "AF59" smd circle
			(at 19.889978 -16.560038 180)
			(size 0.450088 0.450088)
			(layers "F.Cu" "F.Mask" "F.Paste")
			(net "GND")
		)
		(pad "AF60" smd circle
			(at 20.830032 -16.560038 180)
			(size 0.450088 0.450088)
			(layers "F.Cu" "F.Mask" "F.Paste")
			(net "M_D_CPU1_SA_DQS_DN<3>")
		)
		(pad "AF61" smd circle
			(at 21.770086 -16.560038 180)
			(size 0.450088 0.450088)
			(layers "F.Cu" "F.Mask" "F.Paste")
			(net "GND")
		)
		(pad "AF62" smd circle
			(at 22.709886 -16.560038 180)
			(size 0.450088 0.450088)
			(layers "F.Cu" "F.Mask" "F.Paste")
			(net "M_B_CPU1_SA_DQS_DN<8>")
		)
		(pad "AF63" smd circle
			(at 23.64994 -16.560038 180)
			(size 0.450088 0.450088)
			(layers "F.Cu" "F.Mask" "F.Paste")
			(net "M_B_CPU1_SA_DQS_DN<3>")
		)
		(pad "AF64" smd circle
			(at 24.589994 -16.560038 180)
			(size 0.450088 0.450088)
			(layers "F.Cu" "F.Mask" "F.Paste")
			(net "PVDDIO_P1")
		)
		(pad "AF65" smd circle
			(at 25.530048 -16.560038 180)
			(size 0.450088 0.450088)
			(layers "F.Cu" "F.Mask" "F.Paste")
			(net "M_F_CPU1_SA_DQS_DN<8>")
		)
		(pad "AF66" smd circle
			(at 26.470102 -16.560038 180)
			(size 0.450088 0.450088)
			(layers "F.Cu" "F.Mask" "F.Paste")
			(net "GND")
		)
		(pad "AF67" smd circle
			(at 27.409902 -16.560038 180)
			(size 0.450088 0.450088)
			(layers "F.Cu" "F.Mask" "F.Paste")
			(net "M_F_CPU1_SA_DQS_DN<3>")
		)
		(pad "AF68" smd circle
			(at 28.349956 -16.560038 180)
			(size 0.450088 0.450088)
			(layers "F.Cu" "F.Mask" "F.Paste")
			(net "GND")
		)
		(pad "AF69" smd circle
			(at 29.29001 -16.560038 180)
			(size 0.450088 0.450088)
			(layers "F.Cu" "F.Mask" "F.Paste")
			(net "M_E_CPU1_SA_DQS_DN<8>")
		)
		(pad "AF70" smd circle
			(at 30.230064 -16.560038 180)
			(size 0.450088 0.450088)
			(layers "F.Cu" "F.Mask" "F.Paste")
			(net "M_E_CPU1_SA_DQS_DN<3>")
		)
		(pad "AF71" smd circle
			(at 31.170118 -16.560038 180)
			(size 0.450088 0.450088)
			(layers "F.Cu" "F.Mask" "F.Paste")
			(net "PVDDIO_P1")
		)
		(pad "AF72" smd circle
			(at 32.109918 -16.560038 180)
			(size 0.450088 0.450088)
			(layers "F.Cu" "F.Mask" "F.Paste")
			(net "M_A_CPU1_SA_DQS_DN<8>")
		)
		(pad "AF73" smd circle
			(at 33.049972 -16.560038 180)
			(size 0.450088 0.450088)
			(layers "F.Cu" "F.Mask" "F.Paste")
			(net "GND")
		)
		(pad "AF74" smd circle
			(at 33.990026 -16.560038 180)
			(size 0.450088 0.450088)
			(layers "F.Cu" "F.Mask" "F.Paste")
			(net "M_A_CPU1_SA_DQS_DN<3>")
		)
		(pad "AG1" smd circle
			(at -34.159952 -15.750032 180)
			(size 0.450088 0.450088)
			(layers "F.Cu" "F.Mask" "F.Paste")
			(net "GND")
		)
		(pad "AG2" smd circle
			(at -33.219898 -15.750032 180)
			(size 0.450088 0.450088)
			(layers "F.Cu" "F.Mask" "F.Paste")
			(net "M_G_CPU1_SA_DQ<28>")
		)
		(pad "AG3" smd circle
			(at -32.280098 -15.750032 180)
			(size 0.450088 0.450088)
			(layers "F.Cu" "F.Mask" "F.Paste")
			(net "M_G_CPU1_SA_DQS_DP<8>")
		)
		(pad "AG4" smd circle
			(at -31.340044 -15.750032 180)
			(size 0.450088 0.450088)
			(layers "F.Cu" "F.Mask" "F.Paste")
			(net "GND")
		)
		(pad "AG5" smd circle
			(at -30.39999 -15.750032 180)
			(size 0.450088 0.450088)
			(layers "F.Cu" "F.Mask" "F.Paste")
			(net "M_K_CPU1_SA_DQ<28>")
		)
		(pad "AG6" smd circle
			(at -29.459936 -15.750032 180)
			(size 0.450088 0.450088)
			(layers "F.Cu" "F.Mask" "F.Paste")
			(net "GND")
		)
		(pad "AG7" smd circle
			(at -28.519882 -15.750032 180)
			(size 0.450088 0.450088)
			(layers "F.Cu" "F.Mask" "F.Paste")
			(net "M_K_CPU1_SA_DQS_DP<8>")
		)
		(pad "AG8" smd circle
			(at -27.580082 -15.750032 180)
			(size 0.450088 0.450088)
			(layers "F.Cu" "F.Mask" "F.Paste")
			(net "GND")
		)
		(pad "AG9" smd circle
			(at -26.640028 -15.750032 180)
			(size 0.450088 0.450088)
			(layers "F.Cu" "F.Mask" "F.Paste")
			(net "M_L_CPU1_SA_DQ<28>")
		)
		(pad "AG10" smd circle
			(at -25.699974 -15.750032 180)
			(size 0.450088 0.450088)
			(layers "F.Cu" "F.Mask" "F.Paste")
			(net "M_L_CPU1_SA_DQS_DP<8>")
		)
		(pad "AG11" smd circle
			(at -24.75992 -15.750032 180)
			(size 0.450088 0.450088)
			(layers "F.Cu" "F.Mask" "F.Paste")
			(net "GND")
		)
		(pad "AG12" smd circle
			(at -23.82012 -15.750032 180)
			(size 0.450088 0.450088)
			(layers "F.Cu" "F.Mask" "F.Paste")
			(net "M_H_CPU1_SA_DQ<28>")
		)
		(pad "AG13" smd circle
			(at -22.880066 -15.750032 180)
			(size 0.450088 0.450088)
			(layers "F.Cu" "F.Mask" "F.Paste")
			(net "GND")
		)
		(pad "AG14" smd circle
			(at -21.940012 -15.750032 180)
			(size 0.450088 0.450088)
			(layers "F.Cu" "F.Mask" "F.Paste")
			(net "M_H_CPU1_SA_DQS_DP<8>")
		)
		(pad "AG15" smd circle
			(at -20.999958 -15.750032 180)
			(size 0.450088 0.450088)
			(layers "F.Cu" "F.Mask" "F.Paste")
			(net "GND")
		)
		(pad "AG16" smd circle
			(at -20.059904 -15.750032 180)
			(size 0.450088 0.450088)
			(layers "F.Cu" "F.Mask" "F.Paste")
			(net "M_J_CPU1_SA_DQ<28>")
		)
		(pad "AG17" smd circle
			(at -19.120104 -15.750032 180)
			(size 0.450088 0.450088)
			(layers "F.Cu" "F.Mask" "F.Paste")
			(net "M_J_CPU1_SA_DQS_DP<8>")
		)
		(pad "AG18" smd circle
			(at -18.18005 -15.750032 180)
			(size 0.450088 0.450088)
			(layers "F.Cu" "F.Mask" "F.Paste")
			(net "GND")
		)
		(pad "AG19" smd circle
			(at -17.239996 -15.750032 180)
			(size 0.450088 0.450088)
			(layers "F.Cu" "F.Mask" "F.Paste")
			(net "M_I_CPU1_SA_DQ<28>")
		)
		(pad "AG20" smd circle
			(at -16.299942 -15.750032 180)
			(size 0.450088 0.450088)
			(layers "F.Cu" "F.Mask" "F.Paste")
			(net "GND")
		)
		(pad "AG21" smd circle
			(at -15.359888 -15.750032 180)
			(size 0.450088 0.450088)
			(layers "F.Cu" "F.Mask" "F.Paste")
			(net "M_I_CPU1_SA_DQS_DP<8>")
		)
		(pad "AG22" smd circle
			(at -14.420088 -15.750032 180)
			(size 0.450088 0.450088)
			(layers "F.Cu" "F.Mask" "F.Paste")
			(net "GND")
		)
		(pad "AG23" smd circle
			(at -13.480034 -15.750032 180)
			(size 0.450088 0.450088)
			(layers "F.Cu" "F.Mask" "F.Paste")
			(net "GMI_CPU0_G0_CPU1_G2_TX_DN<13>")
		)
		(pad "AG24" smd circle
			(at -12.53998 -15.750032 180)
			(size 0.450088 0.450088)
			(layers "F.Cu" "F.Mask" "F.Paste")
			(net "GMI_CPU0_G0_CPU1_G2_TX_DP<13>")
		)
		(pad "AG25" smd circle
			(at -11.599926 -15.750032 180)
			(size 0.450088 0.450088)
			(layers "F.Cu" "F.Mask" "F.Paste")
			(net "GND")
		)
		(pad "AG26" smd circle
			(at -10.659872 -15.750032 180)
			(size 0.450088 0.450088)
			(layers "F.Cu" "F.Mask" "F.Paste")
			(net "GMI_CPU0_G0_CPU1_G2_TX_DN<10>")
		)
		(pad "AG27" smd circle
			(at -9.720072 -15.750032 180)
			(size 0.450088 0.450088)
			(layers "F.Cu" "F.Mask" "F.Paste")
			(net "GMI_CPU0_G0_CPU1_G2_TX_DP<10>")
		)
		(pad "AG28" smd circle
			(at -8.780018 -15.750032 180)
			(size 0.450088 0.450088)
			(layers "F.Cu" "F.Mask" "F.Paste")
			(net "GND")
		)
		(pad "AG29" smd circle
			(at -7.839964 -15.750032 180)
			(size 0.450088 0.450088)
			(layers "F.Cu" "F.Mask" "F.Paste")
			(net "GMI_CPU0_G0_CPU1_G2_TX_DN<7>")
		)
		(pad "AG30" smd circle
			(at -6.89991 -15.750032 180)
			(size 0.450088 0.450088)
			(layers "F.Cu" "F.Mask" "F.Paste")
			(net "GMI_CPU0_G0_CPU1_G2_TX_DP<7>")
		)
		(pad "AG31" smd circle
			(at -5.96011 -15.750032 180)
			(size 0.450088 0.450088)
			(layers "F.Cu" "F.Mask" "F.Paste")
			(net "GND")
		)
		(pad "AG32" smd circle
			(at -5.020056 -15.750032 180)
			(size 0.450088 0.450088)
			(layers "F.Cu" "F.Mask" "F.Paste")
			(net "GMI_CPU0_G0_CPU1_G2_TX_DN<3>")
		)
		(pad "AG33" smd circle
			(at -4.080002 -15.750032 180)
			(size 0.450088 0.450088)
			(layers "F.Cu" "F.Mask" "F.Paste")
			(net "GMI_CPU0_G0_CPU1_G2_TX_DP<3>")
		)
		(pad "AG34" smd circle
			(at -3.139948 -15.750032 180)
			(size 0.450088 0.450088)
			(layers "F.Cu" "F.Mask" "F.Paste")
			(net "GND")
		)
		(pad "AG35" smd circle
			(at -2.199894 -15.750032 180)
			(size 0.450088 0.450088)
			(layers "F.Cu" "F.Mask" "F.Paste")
			(net "PVDDCR_CPU0_P1")
		)
		(pad "AG36" smd circle
			(at -1.260094 -15.750032 180)
			(size 0.450088 0.450088)
			(layers "F.Cu" "F.Mask" "F.Paste")
			(net "PVDDCR_CPU0_P1")
		)
		(pad "AG40" smd circle
			(at 1.560068 -15.750032 180)
			(size 0.450088 0.450088)
			(layers "F.Cu" "F.Mask" "F.Paste")
			(net "PVDDCR_CPU0_P1")
		)
		(pad "AG41" smd circle
			(at 2.500122 -15.750032 180)
			(size 0.450088 0.450088)
			(layers "F.Cu" "F.Mask" "F.Paste")
			(net "PVDDCR_CPU0_P1")
		)
		(pad "AG42" smd circle
			(at 3.439922 -15.750032 180)
			(size 0.450088 0.450088)
			(layers "F.Cu" "F.Mask" "F.Paste")
			(net "GND")
		)
		(pad "AG43" smd circle
			(at 4.379976 -15.750032 180)
			(size 0.450088 0.450088)
			(layers "F.Cu" "F.Mask" "F.Paste")
			(net "GMI_CPU1_G0_CPU0_G2_TX_DP<12>")
		)
		(pad "AG44" smd circle
			(at 5.32003 -15.750032 180)
			(size 0.450088 0.450088)
			(layers "F.Cu" "F.Mask" "F.Paste")
			(net "GMI_CPU1_G0_CPU0_G2_TX_DN<12>")
		)
		(pad "AG45" smd circle
			(at 6.260084 -15.750032 180)
			(size 0.450088 0.450088)
			(layers "F.Cu" "F.Mask" "F.Paste")
			(net "GND")
		)
		(pad "AG46" smd circle
			(at 7.199884 -15.750032 180)
			(size 0.450088 0.450088)
			(layers "F.Cu" "F.Mask" "F.Paste")
			(net "GMI_CPU1_G0_CPU0_G2_TX_DP<8>")
		)
		(pad "AG47" smd circle
			(at 8.139938 -15.750032 180)
			(size 0.450088 0.450088)
			(layers "F.Cu" "F.Mask" "F.Paste")
			(net "GMI_CPU1_G0_CPU0_G2_TX_DN<8>")
		)
		(pad "AG48" smd circle
			(at 9.079992 -15.750032 180)
			(size 0.450088 0.450088)
			(layers "F.Cu" "F.Mask" "F.Paste")
			(net "GND")
		)
		(pad "AG49" smd circle
			(at 10.020046 -15.750032 180)
			(size 0.450088 0.450088)
			(layers "F.Cu" "F.Mask" "F.Paste")
			(net "GMI_CPU1_G0_CPU0_G2_TX_DP<5>")
		)
	)
)
